(kicad_pcb
	(version 20260206)
	(generator "pcbnew")
	(generator_version "10.0")
	(general
		(thickness 1.6)
		(legacy_teardrops no)
	)
	(paper "A4")
	(title_block
		(title "01162023_DA0F0TEBIF0_F0T_Expander_BD_F_brd_V02_OCP.brd")
		(comment 1 "Grand Teton / footprints 3322-3329 of 9728")
	)
	(layers
		(0 "F.Cu" signal "TOP")
		(4 "In1.Cu" signal "GND")
		(6 "In2.Cu" signal "VCC")
		(8 "In3.Cu" signal "VCC1")
		(10 "In4.Cu" signal "GND1")
		(12 "In5.Cu" signal "IN1")
		(14 "In6.Cu" signal "GND2")
		(16 "In7.Cu" signal "IN2")
		(18 "In8.Cu" signal "GND3")
		(20 "In9.Cu" signal "IN3")
		(22 "In10.Cu" signal "GND4")
		(24 "In11.Cu" signal "IN4")
		(26 "In12.Cu" signal "GND5")
		(28 "In13.Cu" signal "IN5")
		(30 "In14.Cu" signal "GND6")
		(32 "In15.Cu" signal "IN6")
		(34 "In16.Cu" signal "GND7")
		(2 "B.Cu" signal "BOTTOM")
		(9 "F.Adhes" user "F.Adhesive")
		(11 "B.Adhes" user "B.Adhesive")
		(13 "F.Paste" user "Package Geometry/Pastemask Top")
		(15 "B.Paste" user "Package Geometry/Pastemask Bottom")
		(5 "F.SilkS" user "Ref Des/Silkscreen Top")
		(7 "B.SilkS" user "Ref Des/Silkscreen Bottom")
		(1 "F.Mask" user "Board Geometry/Soldermask Top")
		(3 "B.Mask" user "Board Geometry/Soldermask Bottom")
		(17 "Dwgs.User" user "User.Drawings")
		(19 "Cmts.User" user "User.Comments")
		(21 "Eco1.User" user "User.Eco1")
		(23 "Eco2.User" user "User.Eco2")
		(25 "Edge.Cuts" user "Board Geometry/Outline")
		(27 "Margin" user)
		(31 "F.CrtYd" user "Package Geometry/Place Bound Top")
		(29 "B.CrtYd" user "Package Geometry/Place Bound Bottom")
		(35 "F.Fab" user "Ref Des/Assembly Top")
		(33 "B.Fab" user "Ref Des/Assembly Bottom")
	)
	(footprint ""
		(layer "F.Cu")
		(at 446.957196 -102.088442)
		(property "Reference" "PC346"
			(at 0 0 0)
			(layer "F.SilkS")
			(hide yes)
			(effects
				(font
					(size 1.27 1.27)
				)
			)
		)
		(property "Value" ""
			(at 0 0 0)
			(layer "F.Fab")
			(effects
				(font
					(size 1.27 1.27)
				)
			)
		)
		(duplicate_pad_numbers_are_jumpers no)
		(fp_line
			(start -0.7874 -0.4064)
			(end 0.7874 -0.4064)
			(stroke
				(width 0.1524)
				(type default)
			)
			(layer "F.SilkS")
		)
		(fp_line
			(start -0.7874 0.4064)
			(end -0.7874 -0.4064)
			(stroke
				(width 0.1524)
				(type default)
			)
			(layer "F.SilkS")
		)
		(fp_line
			(start 0.7874 -0.4064)
			(end 0.7874 0.4064)
			(stroke
				(width 0.1524)
				(type default)
			)
			(layer "F.SilkS")
		)
		(fp_line
			(start 0.7874 0.4064)
			(end -0.7874 0.4064)
			(stroke
				(width 0.1524)
				(type default)
			)
			(layer "F.SilkS")
		)
		(fp_line
			(start -0.67945 -0.305054)
			(end -0.12065 -0.305054)
			(stroke
				(width 0.1)
				(type default)
			)
			(layer "F.Fab")
		)
		(fp_line
			(start -0.67945 0.3048)
			(end -0.67945 -0.305054)
			(stroke
				(width 0.1)
				(type default)
			)
			(layer "F.Fab")
		)
		(fp_line
			(start -0.12065 -0.305054)
			(end -0.12065 -0.2794)
			(stroke
				(width 0.1)
				(type default)
			)
			(layer "F.Fab")
		)
		(fp_line
			(start -0.12065 -0.2794)
			(end 0.12065 -0.2794)
			(stroke
				(width 0.1)
				(type default)
			)
			(layer "F.Fab")
		)
		(fp_line
			(start -0.12065 0.2794)
			(end -0.12065 0.3048)
			(stroke
				(width 0.1)
				(type default)
			)
			(layer "F.Fab")
		)
		(fp_line
			(start -0.12065 0.3048)
			(end -0.67945 0.3048)
			(stroke
				(width 0.1)
				(type default)
			)
			(layer "F.Fab")
		)
		(fp_line
			(start 0.120396 0.2794)
			(end -0.12065 0.2794)
			(stroke
				(width 0.1)
				(type default)
			)
			(layer "F.Fab")
		)
		(fp_line
			(start 0.120396 0.3048)
			(end 0.120396 0.2794)
			(stroke
				(width 0.1)
				(type default)
			)
			(layer "F.Fab")
		)
		(fp_line
			(start 0.12065 -0.3048)
			(end 0.67945 -0.3048)
			(stroke
				(width 0.1)
				(type default)
			)
			(layer "F.Fab")
		)
		(fp_line
			(start 0.12065 -0.2794)
			(end 0.12065 -0.3048)
			(stroke
				(width 0.1)
				(type default)
			)
			(layer "F.Fab")
		)
		(fp_line
			(start 0.67945 -0.3048)
			(end 0.67945 0.3048)
			(stroke
				(width 0.1)
				(type default)
			)
			(layer "F.Fab")
		)
		(fp_line
			(start 0.67945 0.3048)
			(end 0.120396 0.3048)
			(stroke
				(width 0.1)
				(type default)
			)
			(layer "F.Fab")
		)
		(pad "1" smd circle
			(at -0.40005 0)
			(size 0 0)
			(layers "F.Cu" "F.Mask" "F.Paste")
			(net "P12V_NIC7_R")
		)
		(pad "2" smd circle
			(at 0.40005 0)
			(size 0 0)
			(layers "F.Cu" "F.Mask" "F.Paste")
			(net "GND")
		)
	)
	(footprint ""
		(layer "F.Cu")
		(at 358.41051 -126.995428 180)
		(property "Reference" "PC483"
			(at 0 0 180)
			(layer "F.SilkS")
			(hide yes)
			(effects
				(font
					(size 1.27 1.27)
				)
			)
		)
		(property "Value" ""
			(at 0 0 180)
			(layer "F.Fab")
			(effects
				(font
					(size 1.27 1.27)
				)
			)
		)
		(duplicate_pad_numbers_are_jumpers no)
		(fp_line
			(start 0.7874 0.4064)
			(end -0.7874 0.4064)
			(stroke
				(width 0.1524)
				(type default)
			)
			(layer "F.SilkS")
		)
		(fp_line
			(start 0.7874 -0.4064)
			(end 0.7874 0.4064)
			(stroke
				(width 0.1524)
				(type default)
			)
			(layer "F.SilkS")
		)
		(fp_line
			(start -0.7874 0.4064)
			(end -0.7874 -0.4064)
			(stroke
				(width 0.1524)
				(type default)
			)
			(layer "F.SilkS")
		)
		(fp_line
			(start -0.7874 -0.4064)
			(end 0.7874 -0.4064)
			(stroke
				(width 0.1524)
				(type default)
			)
			(layer "F.SilkS")
		)
		(fp_line
			(start 0.67945 0.3048)
			(end 0.120396 0.3048)
			(stroke
				(width 0.1)
				(type default)
			)
			(layer "F.Fab")
		)
		(fp_line
			(start 0.67945 -0.3048)
			(end 0.67945 0.3048)
			(stroke
				(width 0.1)
				(type default)
			)
			(layer "F.Fab")
		)
		(fp_line
			(start 0.12065 -0.2794)
			(end 0.12065 -0.3048)
			(stroke
				(width 0.1)
				(type default)
			)
			(layer "F.Fab")
		)
		(fp_line
			(start 0.12065 -0.3048)
			(end 0.67945 -0.3048)
			(stroke
				(width 0.1)
				(type default)
			)
			(layer "F.Fab")
		)
		(fp_line
			(start 0.120396 0.3048)
			(end 0.120396 0.2794)
			(stroke
				(width 0.1)
				(type default)
			)
			(layer "F.Fab")
		)
		(fp_line
			(start 0.120396 0.2794)
			(end -0.12065 0.2794)
			(stroke
				(width 0.1)
				(type default)
			)
			(layer "F.Fab")
		)
		(fp_line
			(start -0.12065 0.3048)
			(end -0.67945 0.3048)
			(stroke
				(width 0.1)
				(type default)
			)
			(layer "F.Fab")
		)
		(fp_line
			(start -0.12065 0.2794)
			(end -0.12065 0.3048)
			(stroke
				(width 0.1)
				(type default)
			)
			(layer "F.Fab")
		)
		(fp_line
			(start -0.12065 -0.2794)
			(end 0.12065 -0.2794)
			(stroke
				(width 0.1)
				(type default)
			)
			(layer "F.Fab")
		)
		(fp_line
			(start -0.12065 -0.305054)
			(end -0.12065 -0.2794)
			(stroke
				(width 0.1)
				(type default)
			)
			(layer "F.Fab")
		)
		(fp_line
			(start -0.67945 0.3048)
			(end -0.67945 -0.305054)
			(stroke
				(width 0.1)
				(type default)
			)
			(layer "F.Fab")
		)
		(fp_line
			(start -0.67945 -0.305054)
			(end -0.12065 -0.305054)
			(stroke
				(width 0.1)
				(type default)
			)
			(layer "F.Fab")
		)
		(pad "1" smd circle
			(at -0.40005 0 180)
			(size 0 0)
			(layers "F.Cu" "F.Mask" "F.Paste")
			(net "P3V3_NIC6_SS")
		)
		(pad "2" smd circle
			(at 0.40005 0 180)
			(size 0 0)
			(layers "F.Cu" "F.Mask" "F.Paste")
			(net "GND")
		)
	)
	(footprint ""
		(layer "F.Cu")
		(at 298.961302 -350.098614 90)
		(property "Reference" "C583"
			(at 0 0 90)
			(layer "F.SilkS")
			(hide yes)
			(effects
				(font
					(size 1.27 1.27)
				)
			)
		)
		(property "Value" ""
			(at 0 0 90)
			(layer "F.Fab")
			(effects
				(font
					(size 1.27 1.27)
				)
			)
		)
		(duplicate_pad_numbers_are_jumpers no)
		(fp_line
			(start 0.299974 -0.150114)
			(end 0.299974 0.150114)
			(stroke
				(width 0.1)
				(type default)
			)
			(layer "F.Fab")
		)
		(fp_line
			(start -0.299974 -0.150114)
			(end 0.299974 -0.150114)
			(stroke
				(width 0.1)
				(type default)
			)
			(layer "F.Fab")
		)
		(fp_line
			(start 0.299974 0.150114)
			(end -0.299974 0.150114)
			(stroke
				(width 0.1)
				(type default)
			)
			(layer "F.Fab")
		)
		(fp_line
			(start -0.299974 0.150114)
			(end -0.299974 -0.150114)
			(stroke
				(width 0.1)
				(type default)
			)
			(layer "F.Fab")
		)
		(pad "1" smd rect
			(at -0.2667 0 90)
			(size 0.3048 0.381)
			(layers "F.Cu" "F.Mask" "F.Paste")
			(net "P5E_PEX2_STN7_TX_DP<127>")
		)
		(pad "2" smd rect
			(at 0.2667 0 90)
			(size 0.3048 0.381)
			(layers "F.Cu" "F.Mask" "F.Paste")
			(net "P5E_PEX2_STN7_TX_C_DP<127>")
		)
	)
	(footprint ""
		(layer "F.Cu")
		(at 6.363716 -74.322432 180)
		(property "Reference" "C3667"
			(at 0 0 180)
			(layer "F.SilkS")
			(hide yes)
			(effects
				(font
					(size 1.27 1.27)
				)
			)
		)
		(property "Value" ""
			(at 0 0 180)
			(layer "F.Fab")
			(effects
				(font
					(size 1.27 1.27)
				)
			)
		)
		(duplicate_pad_numbers_are_jumpers no)
		(fp_line
			(start 0.7874 0.4064)
			(end -0.7874 0.4064)
			(stroke
				(width 0.1524)
				(type default)
			)
			(layer "F.SilkS")
		)
		(fp_line
			(start 0.7874 -0.4064)
			(end 0.7874 0.4064)
			(stroke
				(width 0.1524)
				(type default)
			)
			(layer "F.SilkS")
		)
		(fp_line
			(start -0.7874 0.4064)
			(end -0.7874 -0.4064)
			(stroke
				(width 0.1524)
				(type default)
			)
			(layer "F.SilkS")
		)
		(fp_line
			(start -0.7874 -0.4064)
			(end 0.7874 -0.4064)
			(stroke
				(width 0.1524)
				(type default)
			)
			(layer "F.SilkS")
		)
		(fp_line
			(start 0.67945 0.3048)
			(end 0.120396 0.3048)
			(stroke
				(width 0.1)
				(type default)
			)
			(layer "F.Fab")
		)
		(fp_line
			(start 0.67945 -0.3048)
			(end 0.67945 0.3048)
			(stroke
				(width 0.1)
				(type default)
			)
			(layer "F.Fab")
		)
		(fp_line
			(start 0.12065 -0.2794)
			(end 0.12065 -0.3048)
			(stroke
				(width 0.1)
				(type default)
			)
			(layer "F.Fab")
		)
		(fp_line
			(start 0.12065 -0.3048)
			(end 0.67945 -0.3048)
			(stroke
				(width 0.1)
				(type default)
			)
			(layer "F.Fab")
		)
		(fp_line
			(start 0.120396 0.3048)
			(end 0.120396 0.2794)
			(stroke
				(width 0.1)
				(type default)
			)
			(layer "F.Fab")
		)
		(fp_line
			(start 0.120396 0.2794)
			(end -0.12065 0.2794)
			(stroke
				(width 0.1)
				(type default)
			)
			(layer "F.Fab")
		)
		(fp_line
			(start -0.12065 0.3048)
			(end -0.67945 0.3048)
			(stroke
				(width 0.1)
				(type default)
			)
			(layer "F.Fab")
		)
		(fp_line
			(start -0.12065 0.2794)
			(end -0.12065 0.3048)
			(stroke
				(width 0.1)
				(type default)
			)
			(layer "F.Fab")
		)
		(fp_line
			(start -0.12065 -0.2794)
			(end 0.12065 -0.2794)
			(stroke
				(width 0.1)
				(type default)
			)
			(layer "F.Fab")
		)
		(fp_line
			(start -0.12065 -0.305054)
			(end -0.12065 -0.2794)
			(stroke
				(width 0.1)
				(type default)
			)
			(layer "F.Fab")
		)
		(fp_line
			(start -0.67945 0.3048)
			(end -0.67945 -0.305054)
			(stroke
				(width 0.1)
				(type default)
			)
			(layer "F.Fab")
		)
		(fp_line
			(start -0.67945 -0.305054)
			(end -0.12065 -0.305054)
			(stroke
				(width 0.1)
				(type default)
			)
			(layer "F.Fab")
		)
		(pad "1" smd circle
			(at -0.40005 0 180)
			(size 0 0)
			(layers "F.Cu" "F.Mask" "F.Paste")
			(net "P3V3_AUX")
		)
		(pad "2" smd circle
			(at 0.40005 0 180)
			(size 0 0)
			(layers "F.Cu" "F.Mask" "F.Paste")
			(net "GND")
		)
	)
	(footprint ""
		(layer "F.Cu")
		(at 140.074142 -176.913286 180)
		(property "Reference" "R1101"
			(at 0 0 180)
			(layer "F.SilkS")
			(hide yes)
			(effects
				(font
					(size 1.27 1.27)
				)
			)
		)
		(property "Value" ""
			(at 0 0 180)
			(layer "F.Fab")
			(effects
				(font
					(size 1.27 1.27)
				)
			)
		)
		(duplicate_pad_numbers_are_jumpers no)
		(fp_line
			(start 0.7874 0.4064)
			(end -0.7874 0.4064)
			(stroke
				(width 0.1524)
				(type default)
			)
			(layer "F.SilkS")
		)
		(fp_line
			(start 0.67945 0.3048)
			(end 0.120396 0.3048)
			(stroke
				(width 0.1)
				(type default)
			)
			(layer "F.Fab")
		)
		(fp_line
			(start 0.67945 -0.3048)
			(end 0.67945 0.3048)
			(stroke
				(width 0.1)
				(type default)
			)
			(layer "F.Fab")
		)
		(fp_line
			(start 0.12065 -0.2794)
			(end 0.12065 -0.3048)
			(stroke
				(width 0.1)
				(type default)
			)
			(layer "F.Fab")
		)
		(fp_line
			(start 0.12065 -0.3048)
			(end 0.67945 -0.3048)
			(stroke
				(width 0.1)
				(type default)
			)
			(layer "F.Fab")
		)
		(fp_line
			(start 0.120396 0.3048)
			(end 0.120396 0.2794)
			(stroke
				(width 0.1)
				(type default)
			)
			(layer "F.Fab")
		)
		(fp_line
			(start 0.120396 0.2794)
			(end -0.12065 0.2794)
			(stroke
				(width 0.1)
				(type default)
			)
			(layer "F.Fab")
		)
		(fp_line
			(start -0.12065 0.3048)
			(end -0.67945 0.3048)
			(stroke
				(width 0.1)
				(type default)
			)
			(layer "F.Fab")
		)
		(fp_line
			(start -0.12065 0.2794)
			(end -0.12065 0.3048)
			(stroke
				(width 0.1)
				(type default)
			)
			(layer "F.Fab")
		)
		(fp_line
			(start -0.12065 -0.2794)
			(end 0.12065 -0.2794)
			(stroke
				(width 0.1)
				(type default)
			)
			(layer "F.Fab")
		)
		(fp_line
			(start -0.12065 -0.305054)
			(end -0.12065 -0.2794)
			(stroke
				(width 0.1)
				(type default)
			)
			(layer "F.Fab")
		)
		(fp_line
			(start -0.67945 0.3048)
			(end -0.67945 -0.305054)
			(stroke
				(width 0.1)
				(type default)
			)
			(layer "F.Fab")
		)
		(fp_line
			(start -0.67945 -0.305054)
			(end -0.12065 -0.305054)
			(stroke
				(width 0.1)
				(type default)
			)
			(layer "F.Fab")
		)
		(pad "1" smd circle
			(at -0.40005 0 180)
			(size 0 0)
			(layers "F.Cu" "F.Mask" "F.Paste")
			(net "CLK_100M_DB2000QL_NIC3_R_DN")
		)
		(pad "2" smd circle
			(at 0.40005 0 180)
			(size 0 0)
			(layers "F.Cu" "F.Mask" "F.Paste")
			(net "CLK_100M_DB2000QL_NIC3_DN")
		)
	)
	(footprint ""
		(layer "F.Cu")
		(at 168.065196 -5.999988 90)
		(property "Reference" "H52"
			(at 5.34289 -4.22529 0)
			(unlocked yes)
			(layer "F.SilkS")
			(effects
				(font
					(size 0.7874 0.5842)
					(thickness 0.1524)
				)
				(justify left)
			)
		)
		(property "Value" ""
			(at 0 0 90)
			(layer "F.Fab")
			(effects
				(font
					(size 1.27 1.27)
				)
			)
		)
		(duplicate_pad_numbers_are_jumpers no)
		(pad "1" thru_hole circle
			(at 0 0 90)
			(size 10.0076 10.0076)
			(drill 5.6134)
			(layers "*.Cu" "*.Mask")
			(remove_unused_layers no)
			(net "GND")
			(clearance -1.9431)
		)
	)
	(footprint ""
		(layer "F.Cu")
		(at 114.582194 -38.041072 180)
		(property "Reference" "R6060"
			(at 0 0 180)
			(layer "F.SilkS")
			(hide yes)
			(effects
				(font
					(size 1.27 1.27)
				)
			)
		)
		(property "Value" ""
			(at 0 0 180)
			(layer "F.Fab")
			(effects
				(font
					(size 1.27 1.27)
				)
			)
		)
		(duplicate_pad_numbers_are_jumpers no)
		(fp_line
			(start 0.7874 0.4064)
			(end -0.7874 0.4064)
			(stroke
				(width 0.1524)
				(type default)
			)
			(layer "F.SilkS")
		)
		(fp_line
			(start 0.7874 -0.4064)
			(end 0.7874 0.4064)
			(stroke
				(width 0.1524)
				(type default)
			)
			(layer "F.SilkS")
		)
		(fp_line
			(start -0.7874 0.4064)
			(end -0.7874 -0.4064)
			(stroke
				(width 0.1524)
				(type default)
			)
			(layer "F.SilkS")
		)
		(fp_line
			(start -0.7874 -0.4064)
			(end 0.7874 -0.4064)
			(stroke
				(width 0.1524)
				(type default)
			)
			(layer "F.SilkS")
		)
		(fp_line
			(start 0.67945 0.3048)
			(end 0.120396 0.3048)
			(stroke
				(width 0.1)
				(type default)
			)
			(layer "F.Fab")
		)
		(fp_line
			(start 0.67945 -0.3048)
			(end 0.67945 0.3048)
			(stroke
				(width 0.1)
				(type default)
			)
			(layer "F.Fab")
		)
		(fp_line
			(start 0.12065 -0.2794)
			(end 0.12065 -0.3048)
			(stroke
				(width 0.1)
				(type default)
			)
			(layer "F.Fab")
		)
		(fp_line
			(start 0.12065 -0.3048)
			(end 0.67945 -0.3048)
			(stroke
				(width 0.1)
				(type default)
			)
			(layer "F.Fab")
		)
		(fp_line
			(start 0.120396 0.3048)
			(end 0.120396 0.2794)
			(stroke
				(width 0.1)
				(type default)
			)
			(layer "F.Fab")
		)
		(fp_line
			(start 0.120396 0.2794)
			(end -0.12065 0.2794)
			(stroke
				(width 0.1)
				(type default)
			)
			(layer "F.Fab")
		)
		(fp_line
			(start -0.12065 0.3048)
			(end -0.67945 0.3048)
			(stroke
				(width 0.1)
				(type default)
			)
			(layer "F.Fab")
		)
		(fp_line
			(start -0.12065 0.2794)
			(end -0.12065 0.3048)
			(stroke
				(width 0.1)
				(type default)
			)
			(layer "F.Fab")
		)
		(fp_line
			(start -0.12065 -0.2794)
			(end 0.12065 -0.2794)
			(stroke
				(width 0.1)
				(type default)
			)
			(layer "F.Fab")
		)
		(fp_line
			(start -0.12065 -0.305054)
			(end -0.12065 -0.2794)
			(stroke
				(width 0.1)
				(type default)
			)
			(layer "F.Fab")
		)
		(fp_line
			(start -0.67945 0.3048)
			(end -0.67945 -0.305054)
			(stroke
				(width 0.1)
				(type default)
			)
			(layer "F.Fab")
		)
		(fp_line
			(start -0.67945 -0.305054)
			(end -0.12065 -0.305054)
			(stroke
				(width 0.1)
				(type default)
			)
			(layer "F.Fab")
		)
		(pad "1" smd circle
			(at -0.40005 0 180)
			(size 0 0)
			(layers "F.Cu" "F.Mask" "F.Paste")
			(net "P5V_AUX")
		)
		(pad "2" smd circle
			(at 0.40005 0 180)
			(size 0 0)
			(layers "F.Cu" "F.Mask" "F.Paste")
			(net "P3V3_SSD4_PG_G2")
		)
	)
	(footprint ""
		(layer "F.Cu")
		(at 230.952294 -182.61838)
		(property "Reference" "R5493"
			(at 0 0 0)
			(layer "F.SilkS")
			(hide yes)
			(effects
				(font
					(size 1.27 1.27)
				)
			)
		)
		(property "Value" ""
			(at 0 0 0)
			(layer "F.Fab")
			(effects
				(font
					(size 1.27 1.27)
				)
			)
		)
		(duplicate_pad_numbers_are_jumpers no)
		(fp_line
			(start -0.7874 -0.4064)
			(end 0.7874 -0.4064)
			(stroke
				(width 0.1524)
				(type default)
			)
			(layer "F.SilkS")
		)
		(fp_line
			(start -0.7874 0.4064)
			(end -0.7874 -0.4064)
			(stroke
				(width 0.1524)
				(type default)
			)
			(layer "F.SilkS")
		)
		(fp_line
			(start 0.7874 -0.4064)
			(end 0.7874 0.4064)
			(stroke
				(width 0.1524)
				(type default)
			)
			(layer "F.SilkS")
		)
		(fp_line
			(start 0.7874 0.4064)
			(end -0.7874 0.4064)
			(stroke
				(width 0.1524)
				(type default)
			)
			(layer "F.SilkS")
		)
		(fp_line
			(start -0.67945 -0.305054)
			(end -0.12065 -0.305054)
			(stroke
				(width 0.1)
				(type default)
			)
			(layer "F.Fab")
		)
		(fp_line
			(start -0.67945 0.3048)
			(end -0.67945 -0.305054)
			(stroke
				(width 0.1)
				(type default)
			)
			(layer "F.Fab")
		)
		(fp_line
			(start -0.12065 -0.305054)
			(end -0.12065 -0.2794)
			(stroke
				(width 0.1)
				(type default)
			)
			(layer "F.Fab")
		)
		(fp_line
			(start -0.12065 -0.2794)
			(end 0.12065 -0.2794)
			(stroke
				(width 0.1)
				(type default)
			)
			(layer "F.Fab")
		)
		(fp_line
			(start -0.12065 0.2794)
			(end -0.12065 0.3048)
			(stroke
				(width 0.1)
				(type default)
			)
			(layer "F.Fab")
		)
		(fp_line
			(start -0.12065 0.3048)
			(end -0.67945 0.3048)
			(stroke
				(width 0.1)
				(type default)
			)
			(layer "F.Fab")
		)
		(fp_line
			(start 0.120396 0.2794)
			(end -0.12065 0.2794)
			(stroke
				(width 0.1)
				(type default)
			)
			(layer "F.Fab")
		)
		(fp_line
			(start 0.120396 0.3048)
			(end 0.120396 0.2794)
			(stroke
				(width 0.1)
				(type default)
			)
			(layer "F.Fab")
		)
		(fp_line
			(start 0.12065 -0.3048)
			(end 0.67945 -0.3048)
			(stroke
				(width 0.1)
				(type default)
			)
			(layer "F.Fab")
		)
		(fp_line
			(start 0.12065 -0.2794)
			(end 0.12065 -0.3048)
			(stroke
				(width 0.1)
				(type default)
			)
			(layer "F.Fab")
		)
		(fp_line
			(start 0.67945 -0.3048)
			(end 0.67945 0.3048)
			(stroke
				(width 0.1)
				(type default)
			)
			(layer "F.Fab")
		)
		(fp_line
			(start 0.67945 0.3048)
			(end 0.120396 0.3048)
			(stroke
				(width 0.1)
				(type default)
			)
			(layer "F.Fab")
		)
		(pad "1" smd circle
			(at -0.40005 0)
			(size 0 0)
			(layers "F.Cu" "F.Mask" "F.Paste")
			(net "RST_BJT_Q15_C")
		)
		(pad "2" smd circle
			(at 0.40005 0)
			(size 0 0)
			(layers "F.Cu" "F.Mask" "F.Paste")
			(net "P3V3_AUX")
		)
	)
)
